FILE_TYPE=LIBRARY_PARTS;
PRIMITIVE 'SOCKET_P_MECH_A','SOCKET_P_MECH_A_LEFT';
  PIN
  END_PIN;
  BODY
    CLASS='MECHANICAL';
    PART_NAME='SOCKET_P_MECH_A';
    PINCOUNT='0';
    BODY_NAME='SOCKET_P_MECH_A';
    PHYS_DES_PREFIX='XLU';    
  END_BODY;
END_PRIMITIVE;
PRIMITIVE 'SOCKET_P_MECH_A_RIGHT';
  PIN
  END_PIN;
  BODY
    CLASS='MECHANICAL';
    PART_NAME='SOCKET_P_MECH_A';
    PINCOUNT='0';
    BODY_NAME='SOCKET_P_MECH_A';
    PHYS_DES_PREFIX='XRU';    
  END_BODY;
END_PRIMITIVE;

END.
